(kicad_pcb
	(version 20260206)
	(generator "pcbnew")
	(generator_version "10.0")
	(general
		(thickness 1.6)
		(legacy_teardrops no)
	)
	(paper "A4")
	(title_block
		(title "peb — Lightning_PEB_BRD.brd")
		(comment 1 "Lightning (Wiwynn / Facebook NVMe JBOF) / footprints 1375-1380 of 2563")
	)
	(layers
		(0 "F.Cu" signal "TOP")
		(4 "In1.Cu" signal "L2GND")
		(6 "In2.Cu" signal "L3")
		(8 "In3.Cu" signal "L4VCC")
		(10 "In4.Cu" signal "L5VCC")
		(12 "In5.Cu" signal "L6")
		(14 "In6.Cu" signal "L7GND")
		(2 "B.Cu" signal "BOTTOM")
		(9 "F.Adhes" user "F.Adhesive")
		(11 "B.Adhes" user "B.Adhesive")
		(13 "F.Paste" user "Package Geometry/Pastemask Top")
		(15 "B.Paste" user "Package Geometry/Pastemask Bottom")
		(5 "F.SilkS" user "Ref Des/Silkscreen Top")
		(7 "B.SilkS" user "Ref Des/Silkscreen Bottom")
		(1 "F.Mask" user "Board Geometry/Soldermask Top")
		(3 "B.Mask" user "Board Geometry/Soldermask Bottom")
		(17 "Dwgs.User" user "User.Drawings")
		(19 "Cmts.User" user "User.Comments")
		(21 "Eco1.User" user "User.Eco1")
		(23 "Eco2.User" user "User.Eco2")
		(25 "Edge.Cuts" user "Board Geometry/Outline")
		(27 "Margin" user)
		(31 "F.CrtYd" user "Package Geometry/Place Bound Top")
		(29 "B.CrtYd" user "Package Geometry/Place Bound Bottom")
		(35 "F.Fab" user "Ref Des/Assembly Top")
		(33 "B.Fab" user "Ref Des/Assembly Bottom")
	)
	(footprint ""
		(layer "F.Cu")
		(at 264.441432 2.31775)
		(property "Reference" "SW20"
			(at 0 0 0)
			(layer "F.SilkS")
			(hide yes)
			(effects
				(font
					(size 1.27 1.27)
				)
			)
		)
		(property "Value" "SW-SLIDE74-GP"
			(at -4.272534 -5.45465 0)
			(unlocked yes)
			(layer "F.Fab")
			(hide yes)
			(effects
				(font
					(size 1.016 1.016)
					(thickness 0.1524)
				)
			)
		)
		(property "Device Type" "LSSM12-P-V-TR"
			(at -4.272534 -6.97865 0)
			(unlocked yes)
			(layer "F.Fab")
			(hide yes)
			(effects
				(font
					(size 1.016 1.016)
					(thickness 0.1524)
				)
			)
		)
		(duplicate_pad_numbers_are_jumpers no)
		(fp_line
			(start -5.0038 -2.0066)
			(end -3.3528 -2.0066)
			(stroke
				(width 0.1524)
				(type default)
			)
			(layer "F.SilkS")
		)
		(fp_line
			(start -5.0038 2.2098)
			(end -5.0038 -2.0066)
			(stroke
				(width 0.1524)
				(type default)
			)
			(layer "F.SilkS")
		)
		(fp_line
			(start -3.3528 -4.2418)
			(end 3.3528 -4.2418)
			(stroke
				(width 0.1524)
				(type default)
			)
			(layer "F.SilkS")
		)
		(fp_line
			(start -3.3528 -2.0066)
			(end -3.3528 -4.2418)
			(stroke
				(width 0.1524)
				(type default)
			)
			(layer "F.SilkS")
		)
		(fp_line
			(start -2.2987 -4.3688)
			(end -2.6797 -4.3688)
			(stroke
				(width 0.3302)
				(type default)
			)
			(layer "F.SilkS")
		)
		(fp_line
			(start -2.0066 2.2098)
			(end -5.0038 2.2098)
			(stroke
				(width 0.1524)
				(type default)
			)
			(layer "F.SilkS")
		)
		(fp_line
			(start -2.0066 4.0132)
			(end -2.0066 2.2098)
			(stroke
				(width 0.1524)
				(type default)
			)
			(layer "F.SilkS")
		)
		(fp_line
			(start 2.0066 2.2098)
			(end 2.0066 4.0132)
			(stroke
				(width 0.1524)
				(type default)
			)
			(layer "F.SilkS")
		)
		(fp_line
			(start 2.0066 4.0132)
			(end -2.0066 4.0132)
			(stroke
				(width 0.1524)
				(type default)
			)
			(layer "F.SilkS")
		)
		(fp_line
			(start 3.3528 -4.2418)
			(end 3.3528 -2.0066)
			(stroke
				(width 0.1524)
				(type default)
			)
			(layer "F.SilkS")
		)
		(fp_line
			(start 3.3528 -2.0066)
			(end 5.0038 -2.0066)
			(stroke
				(width 0.1524)
				(type default)
			)
			(layer "F.SilkS")
		)
		(fp_line
			(start 5.0038 -2.0066)
			(end 5.0038 2.2098)
			(stroke
				(width 0.1524)
				(type default)
			)
			(layer "F.SilkS")
		)
		(fp_line
			(start 5.0038 2.2098)
			(end 2.0066 2.2098)
			(stroke
				(width 0.1524)
				(type default)
			)
			(layer "F.SilkS")
		)
		(fp_poly
			(pts
				(xy -2.500122 -4.318) (xy -3.008122 -4.826) (xy -1.992122 -4.826)
			)
			(stroke
				(width 0)
				(type default)
			)
			(fill yes)
			(layer "F.SilkS")
		)
		(fp_poly
			(pts
				(xy -1.7526 3.7592) (xy -1.7526 1.9558) (xy -4.7498 1.9558) (xy -4.7498 -1.7526) (xy -2.794 -1.7526)
				(xy -2.794 -3.7592) (xy 2.794 -3.7592) (xy 2.794 -1.7526) (xy 4.7498 -1.7526) (xy 4.7498 1.9558)
				(xy 1.7526 1.9558) (xy 1.7526 3.7592)
			)
			(stroke
				(width 0)
				(type default)
			)
			(fill no)
			(layer "F.CrtYd")
		)
		(fp_poly
			(pts
				(xy -2.2606 4.2672) (xy -2.2606 2.4638) (xy -5.2578 2.4638) (xy -5.2578 -0.1524) (xy -4.7498 -0.1524)
				(xy -4.7498 1.9558) (xy -1.7526 1.9558) (xy -1.7526 3.7592) (xy 1.7526 3.7592) (xy 1.7526 1.9558)
				(xy 4.7498 1.9558) (xy 4.7498 -1.7526) (xy 2.794 -1.7526) (xy 2.794 -3.7592) (xy -2.794 -3.7592)
				(xy -2.794 -1.7526) (xy -4.7498 -1.7526) (xy -4.7498 -0.15748) (xy -5.2578 -0.15748) (xy -5.2578 -2.2606)
				(xy -3.6068 -2.2606) (xy -3.6068 -4.4958) (xy 3.6068 -4.4958) (xy 3.6068 -2.2606) (xy 5.2578 -2.2606)
				(xy 5.2578 2.4638) (xy 2.2606 2.4638) (xy 2.2606 4.2672)
			)
			(stroke
				(width 0)
				(type default)
			)
			(fill no)
			(layer "F.CrtYd")
		)
		(fp_poly
			(pts
				(xy -2.2606 4.2672) (xy -2.2606 2.4638) (xy -5.2578 2.4638) (xy -5.2578 -2.2606) (xy -3.6068 -2.2606)
				(xy -3.6068 -4.4958) (xy 3.6068 -4.4958) (xy 3.6068 -2.2606) (xy 5.2578 -2.2606) (xy 5.2578 2.4638)
				(xy 2.2606 2.4638) (xy 2.2606 4.2672)
			)
			(stroke
				(width 0)
				(type default)
			)
			(fill no)
			(layer "F.Fab")
		)
		(pad "" np_thru_hole circle
			(at -3.400044 0)
			(size 0.254 0.254)
			(drill 0.9652)
			(layers "*.Cu" "*.Mask")
			(clearance 0.7112)
			(thermal_gap 0.7112)
		)
		(pad "" np_thru_hole circle
			(at 3.400044 0)
			(size 0.254 0.254)
			(drill 0.9652)
			(layers "*.Cu" "*.Mask")
			(clearance 0.7112)
			(thermal_gap 0.7112)
		)
		(pad "1" smd rect
			(at -2.500122 -2.750058)
			(size 1.1938 2.4892)
			(layers "F.Cu" "F.Mask" "F.Paste")
			(net "FM_BMC_RESET#_BTN")
		)
		(pad "2" smd rect
			(at 0 -2.750058)
			(size 1.1938 2.4892)
			(layers "F.Cu" "F.Mask" "F.Paste")
			(net "RST_BTN#_R")
		)
		(pad "3" smd rect
			(at 2.500122 -2.750058)
			(size 1.1938 2.4892)
			(layers "F.Cu" "F.Mask" "F.Paste")
			(net "SLIDE_SW_PMC_RST#")
		)
		(zone
			(layers "F.Cu" "B.Cu" "In1.Cu" "In2.Cu" "In3.Cu" "In4.Cu" "In5.Cu" "In6.Cu")
			(hatch none 0.5)
			(connect_pads
				(clearance 0)
			)
			(min_thickness 0.25)
			(keepout
				(tracks not_allowed)
				(vias allowed)
				(pads allowed)
				(copperpour not_allowed)
				(footprints allowed)
			)
			(placement
				(enabled no)
				(sheetname "")
			)
			(fill
				(thermal_gap 0.5)
				(thermal_bridge_width 0.5)
				(island_removal_mode 0)
			)
			(polygon
				(pts
					(arc
						(start 261.828788 2.31775)
						(mid 260.253988 2.31775)
						(end 261.828788 2.31775)
					)
				)
			)
		)
		(zone
			(layers "F.Cu" "B.Cu" "In1.Cu" "In2.Cu" "In3.Cu" "In4.Cu" "In5.Cu" "In6.Cu")
			(hatch none 0.5)
			(connect_pads
				(clearance 0)
			)
			(min_thickness 0.25)
			(keepout
				(tracks not_allowed)
				(vias allowed)
				(pads allowed)
				(copperpour not_allowed)
				(footprints allowed)
			)
			(placement
				(enabled no)
				(sheetname "")
			)
			(fill
				(thermal_gap 0.5)
				(thermal_bridge_width 0.5)
				(island_removal_mode 0)
			)
			(polygon
				(pts
					(arc
						(start 268.628876 2.31775)
						(mid 267.054076 2.31775)
						(end 268.628876 2.31775)
					)
				)
			)
		)
	)
	(footprint ""
		(layer "F.Cu")
		(at 61.0616 -58.9534 180)
		(property "Reference" "R265"
			(at 0 0 180)
			(layer "F.SilkS")
			(hide yes)
			(effects
				(font
					(size 1.27 1.27)
				)
			)
		)
		(property "Value" "0R2J-2-GP"
			(at 0.064008 -3.993896 180)
			(unlocked yes)
			(layer "F.Fab")
			(hide yes)
			(effects
				(font
					(size 1.016 1.016)
					(thickness 0.1524)
				)
			)
		)
		(property "Device Type" "R402H16"
			(at 0.064008 -5.517896 180)
			(unlocked yes)
			(layer "F.Fab")
			(hide yes)
			(effects
				(font
					(size 1.016 1.016)
					(thickness 0.1524)
				)
			)
		)
		(duplicate_pad_numbers_are_jumpers no)
		(fp_line
			(start 0.508 -0.9398)
			(end -0.508 -0.9398)
			(stroke
				(width 0.1524)
				(type default)
			)
			(layer "F.SilkS")
		)
		(fp_line
			(start -0.508 -0.9398)
			(end -0.508 0.9398)
			(stroke
				(width 0.1524)
				(type default)
			)
			(layer "F.SilkS")
		)
		(fp_rect
			(start -0.508 0.9398)
			(end 0.508 -0.9398)
			(stroke
				(width 0)
				(type default)
			)
			(fill no)
			(layer "F.CrtYd")
		)
		(fp_rect
			(start -0.508 0.9398)
			(end 0.508 -0.9398)
			(stroke
				(width 0)
				(type default)
			)
			(fill no)
			(layer "F.Fab")
		)
		(pad "1" smd custom
			(at 0 -0.4445 180)
			(size 0.1397 0.1397)
			(layers "F.Cu" "F.Mask" "F.Paste")
			(net "P3V3_STBY")
			(options
				(clearance outline)
				(anchor circle)
			)
			(primitives
				(gr_poly
					(pts
						(arc
							(start -0.1778 -0.2794)
							(mid -0.249642 -0.249642)
							(end -0.2794 -0.1778)
						)
						(arc
							(start -0.2794 0.1778)
							(mid -0.249642 0.249642)
							(end -0.1778 0.2794)
						)
						(arc
							(start 0.1778 0.2794)
							(mid 0.249642 0.249642)
							(end 0.2794 0.1778)
						)
						(arc
							(start 0.2794 -0.1778)
							(mid 0.249642 -0.249642)
							(end 0.1778 -0.2794)
						)
					)
					(width 0)
					(fill yes)
				)
			)
		)
		(pad "2" smd custom
			(at 0 0.4445 180)
			(size 0.1397 0.1397)
			(layers "F.Cu" "F.Mask" "F.Paste")
			(net "FLA_WPN")
			(options
				(clearance outline)
				(anchor circle)
			)
			(primitives
				(gr_poly
					(pts
						(arc
							(start -0.1778 -0.2794)
							(mid -0.249642 -0.249642)
							(end -0.2794 -0.1778)
						)
						(arc
							(start -0.2794 0.1778)
							(mid -0.249642 0.249642)
							(end -0.1778 0.2794)
						)
						(arc
							(start 0.1778 0.2794)
							(mid 0.249642 0.249642)
							(end 0.2794 0.1778)
						)
						(arc
							(start 0.2794 -0.1778)
							(mid 0.249642 -0.249642)
							(end 0.1778 -0.2794)
						)
					)
					(width 0)
					(fill yes)
				)
			)
		)
	)
	(footprint ""
		(layer "F.Cu")
		(at 313.514486 -33.556448)
		(property "Reference" "C22"
			(at 0 0 0)
			(layer "F.SilkS")
			(hide yes)
			(effects
				(font
					(size 1.27 1.27)
				)
			)
		)
		(property "Value" "SCD22U10V2KX-1GP"
			(at 1.1811 -2.7051 0)
			(unlocked yes)
			(layer "F.Fab")
			(hide yes)
			(effects
				(font
					(size 1.016 1.016)
					(thickness 0.1524)
				)
			)
		)
		(property "Device Type" "C402H22"
			(at 1.1811 -4.2291 0)
			(unlocked yes)
			(layer "F.Fab")
			(hide yes)
			(effects
				(font
					(size 1.016 1.016)
					(thickness 0.1524)
				)
			)
		)
		(duplicate_pad_numbers_are_jumpers no)
		(fp_rect
			(start -0.4318 0.9525)
			(end 0.4318 -0.9525)
			(stroke
				(width 0)
				(type default)
			)
			(fill no)
			(layer "F.CrtYd")
		)
		(fp_rect
			(start -0.4318 0.9525)
			(end 0.4318 -0.9525)
			(stroke
				(width 0)
				(type default)
			)
			(fill no)
			(layer "F.Fab")
		)
		(pad "1" smd custom
			(at 0 -0.4445)
			(size 0.1524 0.1524)
			(layers "F.Cu" "F.Mask" "F.Paste")
			(net "PCIE_TX_CAP_N10")
			(options
				(clearance outline)
				(anchor circle)
			)
			(primitives
				(gr_poly
					(pts
						(arc
							(start 0.3048 -0.2032)
							(mid 0.275042 -0.275042)
							(end 0.2032 -0.3048)
						)
						(arc
							(start -0.2032 -0.3048)
							(mid -0.275042 -0.275042)
							(end -0.3048 -0.2032)
						)
						(arc
							(start -0.3048 0.2032)
							(mid -0.275042 0.275042)
							(end -0.2032 0.3048)
						)
						(arc
							(start 0.2032 0.3048)
							(mid 0.275042 0.275042)
							(end 0.3048 0.2032)
						)
					)
					(width 0)
					(fill yes)
				)
			)
		)
		(pad "2" smd custom
			(at 0 0.4445)
			(size 0.1524 0.1524)
			(layers "F.Cu" "F.Mask" "F.Paste")
			(net "PCIE_TX_N10")
			(options
				(clearance outline)
				(anchor circle)
			)
			(primitives
				(gr_poly
					(pts
						(arc
							(start 0.3048 -0.2032)
							(mid 0.275042 -0.275042)
							(end 0.2032 -0.3048)
						)
						(arc
							(start -0.2032 -0.3048)
							(mid -0.275042 -0.275042)
							(end -0.3048 -0.2032)
						)
						(arc
							(start -0.3048 0.2032)
							(mid -0.275042 0.275042)
							(end -0.2032 0.3048)
						)
						(arc
							(start 0.2032 0.3048)
							(mid 0.275042 0.275042)
							(end 0.3048 0.2032)
						)
					)
					(width 0)
					(fill yes)
				)
			)
		)
	)
	(footprint ""
		(layer "F.Cu")
		(at 145.761202 -62.384432 -90)
		(property "Reference" "PC206"
			(at 0 0 270)
			(layer "F.SilkS")
			(hide yes)
			(effects
				(font
					(size 1.27 1.27)
				)
			)
		)
		(property "Value" "SC10U25V5KX-GP"
			(at -0.0762 -6.1214 270)
			(unlocked yes)
			(layer "F.Fab")
			(hide yes)
			(effects
				(font
					(size 1.016 1.016)
					(thickness 0.1524)
				)
			)
		)
		(property "Device Type" "C805H56"
			(at -0.0762 -8.1534 270)
			(unlocked yes)
			(layer "F.Fab")
			(hide yes)
			(effects
				(font
					(size 1.016 1.016)
					(thickness 0.1524)
				)
			)
		)
		(duplicate_pad_numbers_are_jumpers no)
		(fp_line
			(start 0.635 0)
			(end -0.635 0)
			(stroke
				(width 0.508)
				(type default)
			)
			(layer "F.SilkS")
		)
		(fp_rect
			(start -0.9652 1.778)
			(end 0.9652 -1.778)
			(stroke
				(width 0)
				(type default)
			)
			(fill no)
			(layer "F.CrtYd")
		)
		(fp_poly
			(pts
				(xy -0.9652 -1.778) (xy 0.9652 -1.778) (xy 0.9652 1.778) (xy -0.9652 1.778)
			)
			(stroke
				(width 0)
				(type default)
			)
			(fill no)
			(layer "F.Fab")
		)
		(pad "1" smd rect
			(at 0 -0.9652 270)
			(size 1.397 1.143)
			(layers "F.Cu" "F.Mask" "F.Paste")
			(net "P0V9_VIN")
		)
		(pad "2" smd rect
			(at 0 0.9652 270)
			(size 1.397 1.143)
			(layers "F.Cu" "F.Mask" "F.Paste")
			(net "GND")
		)
	)
	(footprint ""
		(layer "F.Cu")
		(at 9.779 -69.85 180)
		(property "Reference" "C234"
			(at 0 0 180)
			(layer "F.SilkS")
			(hide yes)
			(effects
				(font
					(size 1.27 1.27)
				)
			)
		)
		(property "Value" "SC12P50V2JN-3GP"
			(at 1.1811 -2.7051 180)
			(unlocked yes)
			(layer "F.Fab")
			(hide yes)
			(effects
				(font
					(size 1.016 1.016)
					(thickness 0.1524)
				)
			)
		)
		(property "Device Type" "C402H24"
			(at 1.1811 -4.2291 180)
			(unlocked yes)
			(layer "F.Fab")
			(hide yes)
			(effects
				(font
					(size 1.016 1.016)
					(thickness 0.1524)
				)
			)
		)
		(duplicate_pad_numbers_are_jumpers no)
		(fp_rect
			(start -0.4318 0.9525)
			(end 0.4318 -0.9525)
			(stroke
				(width 0)
				(type default)
			)
			(fill no)
			(layer "F.CrtYd")
		)
		(fp_rect
			(start -0.4318 0.9525)
			(end 0.4318 -0.9525)
			(stroke
				(width 0)
				(type default)
			)
			(fill no)
			(layer "F.Fab")
		)
		(pad "1" smd custom
			(at 0 -0.4445 180)
			(size 0.1524 0.1524)
			(layers "F.Cu" "F.Mask" "F.Paste")
			(net "GND")
			(options
				(clearance outline)
				(anchor circle)
			)
			(primitives
				(gr_poly
					(pts
						(arc
							(start 0.3048 -0.2032)
							(mid 0.275042 -0.275042)
							(end 0.2032 -0.3048)
						)
						(arc
							(start -0.2032 -0.3048)
							(mid -0.275042 -0.275042)
							(end -0.3048 -0.2032)
						)
						(arc
							(start -0.3048 0.2032)
							(mid -0.275042 0.275042)
							(end -0.2032 0.3048)
						)
						(arc
							(start 0.2032 0.3048)
							(mid 0.275042 0.275042)
							(end 0.3048 0.2032)
						)
					)
					(width 0)
					(fill yes)
				)
			)
		)
		(pad "2" smd custom
			(at 0 0.4445 180)
			(size 0.1524 0.1524)
			(layers "F.Cu" "F.Mask" "F.Paste")
			(net "XTAL_IN_I210_R")
			(options
				(clearance outline)
				(anchor circle)
			)
			(primitives
				(gr_poly
					(pts
						(arc
							(start 0.3048 -0.2032)
							(mid 0.275042 -0.275042)
							(end 0.2032 -0.3048)
						)
						(arc
							(start -0.2032 -0.3048)
							(mid -0.275042 -0.275042)
							(end -0.3048 -0.2032)
						)
						(arc
							(start -0.3048 0.2032)
							(mid -0.275042 0.275042)
							(end -0.2032 0.3048)
						)
						(arc
							(start 0.2032 0.3048)
							(mid 0.275042 0.275042)
							(end 0.3048 0.2032)
						)
					)
					(width 0)
					(fill yes)
				)
			)
		)
	)
	(footprint ""
		(layer "F.Cu")
		(at 156.898594 -33.421574 180)
		(property "Reference" "R637"
			(at 0 0 180)
			(layer "F.SilkS")
			(hide yes)
			(effects
				(font
					(size 1.27 1.27)
				)
			)
		)
		(property "Value" "0R2J-2-GP"
			(at 0.064008 -3.993896 180)
			(unlocked yes)
			(layer "F.Fab")
			(hide yes)
			(effects
				(font
					(size 1.016 1.016)
					(thickness 0.1524)
				)
			)
		)
		(property "Device Type" "R402H16"
			(at 0.064008 -5.517896 180)
			(unlocked yes)
			(layer "F.Fab")
			(hide yes)
			(effects
				(font
					(size 1.016 1.016)
					(thickness 0.1524)
				)
			)
		)
		(duplicate_pad_numbers_are_jumpers no)
		(fp_line
			(start 0.508 -0.9398)
			(end -0.508 -0.9398)
			(stroke
				(width 0.1524)
				(type default)
			)
			(layer "F.SilkS")
		)
		(fp_line
			(start -0.508 -0.9398)
			(end -0.508 0.9398)
			(stroke
				(width 0.1524)
				(type default)
			)
			(layer "F.SilkS")
		)
		(fp_rect
			(start -0.508 0.9398)
			(end 0.508 -0.9398)
			(stroke
				(width 0)
				(type default)
			)
			(fill no)
			(layer "F.CrtYd")
		)
		(fp_rect
			(start -0.508 0.9398)
			(end 0.508 -0.9398)
			(stroke
				(width 0)
				(type default)
			)
			(fill no)
			(layer "F.Fab")
		)
		(pad "1" smd custom
			(at 0 -0.4445 180)
			(size 0.1397 0.1397)
			(layers "F.Cu" "F.Mask" "F.Paste")
			(net "8644_USB_DP3")
			(options
				(clearance outline)
				(anchor circle)
			)
			(primitives
				(gr_poly
					(pts
						(arc
							(start -0.1778 -0.2794)
							(mid -0.249642 -0.249642)
							(end -0.2794 -0.1778)
						)
						(arc
							(start -0.2794 0.1778)
							(mid -0.249642 0.249642)
							(end -0.1778 0.2794)
						)
						(arc
							(start 0.1778 0.2794)
							(mid 0.249642 0.249642)
							(end 0.2794 0.1778)
						)
						(arc
							(start 0.2794 -0.1778)
							(mid 0.249642 -0.249642)
							(end 0.1778 -0.2794)
						)
					)
					(width 0)
					(fill yes)
				)
			)
		)
		(pad "2" smd custom
			(at 0 0.4445 180)
			(size 0.1397 0.1397)
			(layers "F.Cu" "F.Mask" "F.Paste")
			(net "P3V3_STBY")
			(options
				(clearance outline)
				(anchor circle)
			)
			(primitives
				(gr_poly
					(pts
						(arc
							(start -0.1778 -0.2794)
							(mid -0.249642 -0.249642)
							(end -0.2794 -0.1778)
						)
						(arc
							(start -0.2794 0.1778)
							(mid -0.249642 0.249642)
							(end -0.1778 0.2794)
						)
						(arc
							(start 0.1778 0.2794)
							(mid 0.249642 0.249642)
							(end 0.2794 0.1778)
						)
						(arc
							(start 0.2794 -0.1778)
							(mid 0.249642 -0.249642)
							(end 0.1778 -0.2794)
						)
					)
					(width 0)
					(fill yes)
				)
			)
		)
	)
)
